(kicad_pcb
	(version 20260206)
	(generator "pcbnew")
	(generator_version "10.0")
	(general
		(thickness 1.6)
		(legacy_teardrops no)
	)
	(paper "A4")
	(title_block
		(title "Wiwynn_Tioga_Pass_MB.brd")
		(comment 1 "Tioga Pass / footprints 2897-2903 of 4770")
	)
	(layers
		(0 "F.Cu" signal "TOP")
		(4 "In1.Cu" signal "L2GND")
		(6 "In2.Cu" signal "L3")
		(8 "In3.Cu" signal "L4GND")
		(10 "In4.Cu" signal "L5")
		(12 "In5.Cu" signal "L6GND")
		(14 "In6.Cu" signal "L7VCC")
		(16 "In7.Cu" signal "L8VCC")
		(18 "In8.Cu" signal "L9GND")
		(20 "In9.Cu" signal "L10")
		(22 "In10.Cu" signal "L11GND")
		(24 "In11.Cu" signal "L12")
		(26 "In12.Cu" signal "L13GND")
		(2 "B.Cu" signal "BOTTOM")
		(9 "F.Adhes" user "F.Adhesive")
		(11 "B.Adhes" user "B.Adhesive")
		(13 "F.Paste" user "Package Geometry/Pastemask Top")
		(15 "B.Paste" user "Package Geometry/Pastemask Bottom")
		(5 "F.SilkS" user "Ref Des/Silkscreen Top")
		(7 "B.SilkS" user "Ref Des/Silkscreen Bottom")
		(1 "F.Mask" user "Board Geometry/Soldermask Top")
		(3 "B.Mask" user "Board Geometry/Soldermask Bottom")
		(17 "Dwgs.User" user "User.Drawings")
		(19 "Cmts.User" user "User.Comments")
		(21 "Eco1.User" user "User.Eco1")
		(23 "Eco2.User" user "User.Eco2")
		(25 "Edge.Cuts" user "Board Geometry/Outline")
		(27 "Margin" user)
		(31 "F.CrtYd" user "Package Geometry/Place Bound Top")
		(29 "B.CrtYd" user "Package Geometry/Place Bound Bottom")
		(35 "F.Fab" user "Ref Des/Assembly Top")
		(33 "B.Fab" user "Ref Des/Assembly Bottom")
	)
	(footprint ""
		(layer "B.Cu")
		(at 473.084906 -19.085052 90)
		(property "Reference" "C8F3"
			(at 0 0 90)
			(layer "B.SilkS")
			(hide yes)
			(effects
				(font
					(size 1.27 1.27)
				)
				(justify mirror)
			)
		)
		(property "Value" ""
			(at 0 0 90)
			(layer "B.Fab")
			(effects
				(font
					(size 1.27 1.27)
				)
				(justify mirror)
			)
		)
		(duplicate_pad_numbers_are_jumpers no)
		(fp_rect
			(start -0.3048 -0.1016)
			(end 0.3048 0.9906)
			(stroke
				(width 0)
				(type default)
			)
			(fill no)
			(layer "B.CrtYd")
		)
		(fp_line
			(start 0.3048 -0.1016)
			(end 0.3048 0.9906)
			(stroke
				(width 0.1)
				(type default)
			)
			(layer "B.Fab")
		)
		(fp_line
			(start -0.3048 -0.1016)
			(end 0.3048 -0.1016)
			(stroke
				(width 0.1)
				(type default)
			)
			(layer "B.Fab")
		)
		(fp_line
			(start 0.3048 0.9906)
			(end -0.3048 0.9906)
			(stroke
				(width 0.1)
				(type default)
			)
			(layer "B.Fab")
		)
		(fp_line
			(start -0.3048 0.9906)
			(end -0.3048 -0.1016)
			(stroke
				(width 0.1)
				(type default)
			)
			(layer "B.Fab")
		)
		(pad "1" smd rect
			(at 0 0 270)
			(size 0.508 0.508)
			(layers "B.Cu" "B.Mask" "B.Paste")
			(net "VR_P3V3_STBY_PHASE")
		)
		(pad "2" smd rect
			(at 0 0.889 270)
			(size 0.508 0.508)
			(layers "B.Cu" "B.Mask" "B.Paste")
			(net "VR_P3V3_STBY_SNUB")
		)
		(zone
			(layer "B.Cu")
			(hatch none 0.5)
			(connect_pads
				(clearance 0)
			)
			(min_thickness 0.25)
			(keepout
				(tracks not_allowed)
				(vias allowed)
				(pads allowed)
				(copperpour not_allowed)
				(footprints allowed)
			)
			(placement
				(enabled no)
				(sheetname "")
			)
			(fill
				(thermal_gap 0.5)
				(thermal_bridge_width 0.5)
				(island_removal_mode 0)
			)
			(polygon
				(pts
					(xy 473.338906 -18.831052) (xy 473.719906 -18.831052) (xy 473.719906 -19.339052) (xy 473.338906 -19.339052)
				)
			)
		)
		(zone
			(layer "B.Cu")
			(hatch none 0.5)
			(connect_pads
				(clearance 0)
			)
			(min_thickness 0.25)
			(keepout
				(tracks allowed)
				(vias not_allowed)
				(pads allowed)
				(copperpour not_allowed)
				(footprints allowed)
			)
			(placement
				(enabled no)
				(sheetname "")
			)
			(fill
				(thermal_gap 0.5)
				(thermal_bridge_width 0.5)
				(island_removal_mode 0)
			)
			(polygon
				(pts
					(xy 473.338906 -18.831052) (xy 473.719906 -18.831052) (xy 473.719906 -19.339052) (xy 473.338906 -19.339052)
				)
			)
		)
	)
	(footprint ""
		(layer "B.Cu")
		(at 449.6435 -24.003 90)
		(property "Reference" "R6W22"
			(at 0.8382 -0.67818 90)
			(unlocked yes)
			(layer "B.SilkS")
			(effects
				(font
					(size 0.4064 0.254)
					(thickness 0.1524)
				)
				(justify left mirror)
			)
		)
		(property "Value" ""
			(at 0 0 90)
			(layer "B.Fab")
			(effects
				(font
					(size 1.27 1.27)
				)
				(justify mirror)
			)
		)
		(duplicate_pad_numbers_are_jumpers no)
		(fp_poly
			(pts
				(xy 0.2794 -0.1016) (xy -0.2794 -0.1016) (xy -0.2794 0.9906) (xy 0.2794 0.9906)
			)
			(stroke
				(width 0)
				(type default)
			)
			(fill no)
			(layer "B.CrtYd")
		)
		(fp_line
			(start 0.2794 -0.1016)
			(end 0.2794 0.9906)
			(stroke
				(width 0.1)
				(type default)
			)
			(layer "B.Fab")
		)
		(fp_line
			(start -0.2794 -0.1016)
			(end 0.2794 -0.1016)
			(stroke
				(width 0.1)
				(type default)
			)
			(layer "B.Fab")
		)
		(fp_line
			(start 0.2794 0.9906)
			(end -0.2794 0.9906)
			(stroke
				(width 0.1)
				(type default)
			)
			(layer "B.Fab")
		)
		(fp_line
			(start -0.2794 0.9906)
			(end -0.2794 -0.1016)
			(stroke
				(width 0.1)
				(type default)
			)
			(layer "B.Fab")
		)
		(pad "1" smd rect
			(at 0 0 270)
			(size 0.508 0.508)
			(layers "B.Cu" "B.Mask" "B.Paste")
			(net "SMB_HOST_STBY_LVC3_SCL")
		)
		(pad "2" smd rect
			(at 0 0.889 270)
			(size 0.508 0.508)
			(layers "B.Cu" "B.Mask" "B.Paste")
			(net "SMB_HOST_STBY_LVC3_SCL_R3")
		)
		(zone
			(layer "B.Cu")
			(hatch none 0.5)
			(connect_pads
				(clearance 0)
			)
			(min_thickness 0.25)
			(keepout
				(tracks allowed)
				(vias not_allowed)
				(pads allowed)
				(copperpour not_allowed)
				(footprints allowed)
			)
			(placement
				(enabled no)
				(sheetname "")
			)
			(fill
				(thermal_gap 0.5)
				(thermal_bridge_width 0.5)
				(island_removal_mode 0)
			)
			(polygon
				(pts
					(xy 449.8975 -24.257) (xy 449.8975 -23.749) (xy 450.2785 -23.749) (xy 450.2785 -24.257)
				)
			)
		)
		(zone
			(layer "B.Cu")
			(hatch none 0.5)
			(connect_pads
				(clearance 0)
			)
			(min_thickness 0.25)
			(keepout
				(tracks not_allowed)
				(vias allowed)
				(pads allowed)
				(copperpour not_allowed)
				(footprints allowed)
			)
			(placement
				(enabled no)
				(sheetname "")
			)
			(fill
				(thermal_gap 0.5)
				(thermal_bridge_width 0.5)
				(island_removal_mode 0)
			)
			(polygon
				(pts
					(xy 450.2785 -24.257) (xy 450.2785 -23.749) (xy 449.8975 -23.749) (xy 449.8975 -24.257)
				)
			)
		)
	)
	(footprint ""
		(layer "B.Cu")
		(at 382.93675 -106.25455)
		(property "Reference" "C3N20"
			(at 0 0 0)
			(layer "B.SilkS")
			(hide yes)
			(effects
				(font
					(size 1.27 1.27)
				)
				(justify mirror)
			)
		)
		(property "Value" ""
			(at 0 0 0)
			(layer "B.Fab")
			(effects
				(font
					(size 1.27 1.27)
				)
				(justify mirror)
			)
		)
		(duplicate_pad_numbers_are_jumpers no)
		(fp_rect
			(start 0.2794 0.9144)
			(end -0.2794 -0.1143)
			(stroke
				(width 0)
				(type default)
			)
			(fill no)
			(layer "B.CrtYd")
		)
		(fp_line
			(start -0.2794 -0.1143)
			(end -0.2794 0.9144)
			(stroke
				(width 0.1)
				(type default)
			)
			(layer "B.Fab")
		)
		(fp_line
			(start -0.2794 0.9144)
			(end 0.2794 0.9144)
			(stroke
				(width 0.1)
				(type default)
			)
			(layer "B.Fab")
		)
		(fp_line
			(start 0.2794 -0.1143)
			(end -0.2794 -0.1143)
			(stroke
				(width 0.1)
				(type default)
			)
			(layer "B.Fab")
		)
		(fp_line
			(start 0.2794 0.9144)
			(end 0.2794 -0.1143)
			(stroke
				(width 0.1)
				(type default)
			)
			(layer "B.Fab")
		)
		(pad "1" smd custom
			(at 0 0 270)
			(size 0.10414 0.10414)
			(layers "B.Cu" "B.Mask" "B.Paste")
			(net "PVNN_PCH_STBY")
			(options
				(clearance outline)
				(anchor circle)
			)
			(primitives
				(gr_poly
					(pts
						(xy -0.20828 -0.08636) (xy -0.20828 0.08636) (xy -0.08636 0.20828) (xy 0.086614 0.20828) (xy 0.20828 0.086614)
						(xy 0.20828 -0.08636) (xy 0.08636 -0.20828) (xy -0.08636 -0.20828)
					)
					(width 0)
					(fill yes)
				)
			)
		)
		(pad "2" smd custom
			(at 0 0.8001 270)
			(size 0.10414 0.10414)
			(layers "B.Cu" "B.Mask" "B.Paste")
			(net "GND")
			(options
				(clearance outline)
				(anchor circle)
			)
			(primitives
				(gr_poly
					(pts
						(xy -0.20828 -0.08636) (xy -0.20828 0.08636) (xy -0.08636 0.20828) (xy 0.086614 0.20828) (xy 0.20828 0.086614)
						(xy 0.20828 -0.08636) (xy 0.08636 -0.20828) (xy -0.08636 -0.20828)
					)
					(width 0)
					(fill yes)
				)
			)
		)
		(zone
			(layer "B.Cu")
			(hatch none 0.5)
			(connect_pads
				(clearance 0)
			)
			(min_thickness 0.25)
			(keepout
				(tracks not_allowed)
				(vias allowed)
				(pads allowed)
				(copperpour not_allowed)
				(footprints allowed)
			)
			(placement
				(enabled no)
				(sheetname "")
			)
			(fill
				(thermal_gap 0.5)
				(thermal_bridge_width 0.5)
				(island_removal_mode 0)
			)
			(polygon
				(pts
					(xy 383.02438 -106.045) (xy 383.02438 -105.664) (xy 382.84912 -105.664) (xy 382.848866 -106.045)
				)
			)
		)
		(zone
			(layer "B.Cu")
			(hatch none 0.5)
			(connect_pads
				(clearance 0)
			)
			(min_thickness 0.25)
			(keepout
				(tracks allowed)
				(vias not_allowed)
				(pads allowed)
				(copperpour not_allowed)
				(footprints allowed)
			)
			(placement
				(enabled no)
				(sheetname "")
			)
			(fill
				(thermal_gap 0.5)
				(thermal_bridge_width 0.5)
				(island_removal_mode 0)
			)
			(polygon
				(pts
					(xy 383.02438 -106.045) (xy 383.02438 -105.664) (xy 382.84912 -105.664) (xy 382.848866 -106.045)
				)
			)
		)
	)
	(footprint ""
		(layer "B.Cu")
		(at 410.3624 -14.097 90)
		(property "Reference" "U2R1"
			(at 0 0 90)
			(layer "B.SilkS")
			(hide yes)
			(effects
				(font
					(size 1.27 1.27)
				)
				(justify mirror)
			)
		)
		(property "Value" "*"
			(at 2.3622 -8.3185 90)
			(unlocked yes)
			(layer "B.Fab")
			(hide yes)
			(effects
				(font
					(size 1.27 1.016)
					(thickness 0.1524)
				)
				(justify mirror)
			)
		)
		(property "Device Type" "TC7PZ14FU-GP_DISCRET-GA1-TC7PZA"
			(at 2.3622 -10.2235 90)
			(unlocked yes)
			(layer "B.Fab")
			(hide yes)
			(effects
				(font
					(size 1.27 1.016)
					(thickness 0.1524)
				)
				(justify mirror)
			)
		)
		(duplicate_pad_numbers_are_jumpers no)
		(fp_line
			(start 1.4478 -1.7018)
			(end 1.4478 1.7018)
			(stroke
				(width 0.1524)
				(type default)
			)
			(layer "B.SilkS")
		)
		(fp_line
			(start -1.4478 -1.7018)
			(end 1.4478 -1.7018)
			(stroke
				(width 0.1524)
				(type default)
			)
			(layer "B.SilkS")
		)
		(fp_line
			(start 1.4478 1.7018)
			(end -1.4478 1.7018)
			(stroke
				(width 0.1524)
				(type default)
			)
			(layer "B.SilkS")
		)
		(fp_line
			(start -1.4478 1.7018)
			(end -1.4478 -1.7018)
			(stroke
				(width 0.1524)
				(type default)
			)
			(layer "B.SilkS")
		)
		(fp_line
			(start 1.5494 1.7907)
			(end 1.5494 0.8255)
			(stroke
				(width 0.3302)
				(type default)
			)
			(layer "B.SilkS")
		)
		(fp_line
			(start 0.5715 1.7907)
			(end 1.5494 1.7907)
			(stroke
				(width 0.3302)
				(type default)
			)
			(layer "B.SilkS")
		)
		(fp_poly
			(pts
				(xy 0.6604 1.7272) (xy 1.016 2.0828) (xy 0.3048 2.0828)
			)
			(stroke
				(width 0)
				(type default)
			)
			(fill yes)
			(layer "B.SilkS")
		)
		(fp_poly
			(pts
				(xy 1.524 -1.778) (xy -1.524 -1.778) (xy -1.524 1.778) (xy 1.524 1.778)
			)
			(stroke
				(width 0)
				(type default)
			)
			(fill no)
			(layer "B.CrtYd")
		)
		(fp_poly
			(pts
				(xy 1.524 -1.778) (xy -1.524 -1.778) (xy -1.524 1.778) (xy 1.524 1.778)
			)
			(stroke
				(width 0)
				(type default)
			)
			(fill no)
			(layer "B.Fab")
		)
		(pad "1" smd rect
			(at 0.65024 0.9398 270)
			(size 0.4064 1.016)
			(layers "B.Cu" "B.Mask" "B.Paste")
			(net "FP_NMI_BTN")
		)
		(pad "2" smd rect
			(at 0 0.9398 270)
			(size 0.4064 1.016)
			(layers "B.Cu" "B.Mask" "B.Paste")
			(net "GND")
		)
		(pad "3" smd rect
			(at -0.65024 0.9398 270)
			(size 0.4064 1.016)
			(layers "B.Cu" "B.Mask" "B.Paste")
			(net "FP_NMI_BTN_OUT_N")
		)
		(pad "4" smd rect
			(at -0.65024 -0.9398 270)
			(size 0.4064 1.016)
			(layers "B.Cu" "B.Mask" "B.Paste")
			(net "FP_NMI_BTN")
		)
		(pad "5" smd rect
			(at 0 -0.9398 270)
			(size 0.4064 1.016)
			(layers "B.Cu" "B.Mask" "B.Paste")
			(net "P3V3_STBY")
		)
		(pad "6" smd rect
			(at 0.65024 -0.9398 270)
			(size 0.4064 1.016)
			(layers "B.Cu" "B.Mask" "B.Paste")
			(net "FP_NMI_BTN_R_N")
		)
	)
	(footprint ""
		(layer "B.Cu")
		(at 253.392432 -140.208 90)
		(property "Reference" "C5G67"
			(at -1.14681 0.76708 180)
			(unlocked yes)
			(layer "B.SilkS")
			(effects
				(font
					(size 0.7874 0.5842)
					(thickness 0.1524)
				)
				(justify mirror)
			)
		)
		(property "Value" ""
			(at 0 0 90)
			(layer "B.Fab")
			(effects
				(font
					(size 1.27 1.27)
				)
				(justify mirror)
			)
		)
		(duplicate_pad_numbers_are_jumpers no)
		(fp_rect
			(start -0.4953 -0.2032)
			(end 0.4953 1.6002)
			(stroke
				(width 0)
				(type default)
			)
			(fill no)
			(layer "B.CrtYd")
		)
		(fp_line
			(start 0.4953 -0.2032)
			(end -0.4953 -0.2032)
			(stroke
				(width 0.1)
				(type default)
			)
			(layer "B.Fab")
		)
		(fp_line
			(start -0.4953 -0.2032)
			(end -0.4953 1.6002)
			(stroke
				(width 0.1)
				(type default)
			)
			(layer "B.Fab")
		)
		(fp_line
			(start 0.4953 1.6002)
			(end 0.4953 -0.2032)
			(stroke
				(width 0.1)
				(type default)
			)
			(layer "B.Fab")
		)
		(fp_line
			(start -0.4953 1.6002)
			(end 0.4953 1.6002)
			(stroke
				(width 0.1)
				(type default)
			)
			(layer "B.Fab")
		)
		(pad "1" smd rect
			(at 0 0 270)
			(size 0.762 0.889)
			(layers "B.Cu" "B.Mask" "B.Paste")
			(net "PVDDQ_DEF")
		)
		(pad "2" smd rect
			(at 0 1.397 270)
			(size 0.762 0.889)
			(layers "B.Cu" "B.Mask" "B.Paste")
			(net "GND")
		)
		(zone
			(layer "B.Cu")
			(hatch none 0.5)
			(connect_pads
				(clearance 0)
			)
			(min_thickness 0.25)
			(keepout
				(tracks not_allowed)
				(vias allowed)
				(pads allowed)
				(copperpour not_allowed)
				(footprints allowed)
			)
			(placement
				(enabled no)
				(sheetname "")
			)
			(fill
				(thermal_gap 0.5)
				(thermal_bridge_width 0.5)
				(island_removal_mode 0)
			)
			(polygon
				(pts
					(xy 253.836932 -139.827) (xy 254.344932 -139.827) (xy 254.344932 -140.589) (xy 253.836932 -140.589)
				)
			)
		)
	)
	(footprint ""
		(layer "B.Cu")
		(at 337.537806 -60.368434)
		(property "Reference" "R2U17"
			(at 0 0 0)
			(layer "B.SilkS")
			(hide yes)
			(effects
				(font
					(size 1.27 1.27)
				)
				(justify mirror)
			)
		)
		(property "Value" ""
			(at 0 0 0)
			(layer "B.Fab")
			(effects
				(font
					(size 1.27 1.27)
				)
				(justify mirror)
			)
		)
		(duplicate_pad_numbers_are_jumpers no)
		(fp_poly
			(pts
				(xy 0.2794 -0.1016) (xy -0.2794 -0.1016) (xy -0.2794 0.9906) (xy 0.2794 0.9906)
			)
			(stroke
				(width 0)
				(type default)
			)
			(fill no)
			(layer "B.CrtYd")
		)
		(fp_line
			(start -0.2794 -0.1016)
			(end 0.2794 -0.1016)
			(stroke
				(width 0.1)
				(type default)
			)
			(layer "B.Fab")
		)
		(fp_line
			(start -0.2794 0.9906)
			(end -0.2794 -0.1016)
			(stroke
				(width 0.1)
				(type default)
			)
			(layer "B.Fab")
		)
		(fp_line
			(start 0.2794 -0.1016)
			(end 0.2794 0.9906)
			(stroke
				(width 0.1)
				(type default)
			)
			(layer "B.Fab")
		)
		(fp_line
			(start 0.2794 0.9906)
			(end -0.2794 0.9906)
			(stroke
				(width 0.1)
				(type default)
			)
			(layer "B.Fab")
		)
		(pad "1" smd rect
			(at 0 0 180)
			(size 0.508 0.508)
			(layers "B.Cu" "B.Mask" "B.Paste")
			(net "P3E_CPU0_PE1_SS_RXN<1>")
		)
		(pad "2" smd rect
			(at 0 0.889 180)
			(size 0.508 0.508)
			(layers "B.Cu" "B.Mask" "B.Paste")
			(net "P3E_CPU0_PE1_SS_R_RXN<1>")
		)
		(zone
			(layer "B.Cu")
			(hatch none 0.5)
			(connect_pads
				(clearance 0)
			)
			(min_thickness 0.25)
			(keepout
				(tracks allowed)
				(vias not_allowed)
				(pads allowed)
				(copperpour not_allowed)
				(footprints allowed)
			)
			(placement
				(enabled no)
				(sheetname "")
			)
			(fill
				(thermal_gap 0.5)
				(thermal_bridge_width 0.5)
				(island_removal_mode 0)
			)
			(polygon
				(pts
					(xy 337.791806 -60.114434) (xy 337.283806 -60.114434) (xy 337.283806 -59.733434) (xy 337.791806 -59.733434)
				)
			)
		)
		(zone
			(layer "B.Cu")
			(hatch none 0.5)
			(connect_pads
				(clearance 0)
			)
			(min_thickness 0.25)
			(keepout
				(tracks not_allowed)
				(vias allowed)
				(pads allowed)
				(copperpour not_allowed)
				(footprints allowed)
			)
			(placement
				(enabled no)
				(sheetname "")
			)
			(fill
				(thermal_gap 0.5)
				(thermal_bridge_width 0.5)
				(island_removal_mode 0)
			)
			(polygon
				(pts
					(xy 337.791806 -59.733434) (xy 337.283806 -59.733434) (xy 337.283806 -60.114434) (xy 337.791806 -60.114434)
				)
			)
		)
	)
	(footprint ""
		(layer "B.Cu")
		(at 19.05 -45.72)
		(property "Reference" "C9R13"
			(at 0 0 0)
			(layer "B.SilkS")
			(hide yes)
			(effects
				(font
					(size 1.27 1.27)
				)
				(justify mirror)
			)
		)
		(property "Value" ""
			(at 0 0 0)
			(layer "B.Fab")
			(effects
				(font
					(size 1.27 1.27)
				)
				(justify mirror)
			)
		)
		(duplicate_pad_numbers_are_jumpers no)
		(fp_poly
			(pts
				(xy -0.3048 -0.1016) (xy -0.3048 0.9906) (xy 0.3048 0.9906) (xy 0.3048 -0.1016)
			)
			(stroke
				(width 0)
				(type default)
			)
			(fill no)
			(layer "B.CrtYd")
		)
		(fp_line
			(start -0.3048 -0.1016)
			(end 0.3048 -0.1016)
			(stroke
				(width 0.1)
				(type default)
			)
			(layer "B.Fab")
		)
		(fp_line
			(start -0.3048 0.9906)
			(end -0.3048 -0.1016)
			(stroke
				(width 0.1)
				(type default)
			)
			(layer "B.Fab")
		)
		(fp_line
			(start 0.3048 -0.1016)
			(end 0.3048 0.9906)
			(stroke
				(width 0.1)
				(type default)
			)
			(layer "B.Fab")
		)
		(fp_line
			(start 0.3048 0.9906)
			(end -0.3048 0.9906)
			(stroke
				(width 0.1)
				(type default)
			)
			(layer "B.Fab")
		)
		(pad "1" smd rect
			(at 0 0 180)
			(size 0.508 0.508)
			(layers "B.Cu" "B.Mask" "B.Paste")
			(net "P3V3_STBY")
		)
		(pad "2" smd rect
			(at 0 0.889 180)
			(size 0.508 0.508)
			(layers "B.Cu" "B.Mask" "B.Paste")
			(net "GND")
		)
		(zone
			(layer "B.Cu")
			(hatch none 0.5)
			(connect_pads
				(clearance 0)
			)
			(min_thickness 0.25)
			(keepout
				(tracks allowed)
				(vias not_allowed)
				(pads allowed)
				(copperpour not_allowed)
				(footprints allowed)
			)
			(placement
				(enabled no)
				(sheetname "")
			)
			(fill
				(thermal_gap 0.5)
				(thermal_bridge_width 0.5)
				(island_removal_mode 0)
			)
			(polygon
				(pts
					(xy 19.304 -45.466) (xy 18.796 -45.466) (xy 18.796 -45.085) (xy 19.304 -45.085)
				)
			)
		)
		(zone
			(layer "B.Cu")
			(hatch none 0.5)
			(connect_pads
				(clearance 0)
			)
			(min_thickness 0.25)
			(keepout
				(tracks not_allowed)
				(vias allowed)
				(pads allowed)
				(copperpour not_allowed)
				(footprints allowed)
			)
			(placement
				(enabled no)
				(sheetname "")
			)
			(fill
				(thermal_gap 0.5)
				(thermal_bridge_width 0.5)
				(island_removal_mode 0)
			)
			(polygon
				(pts
					(xy 19.304 -45.085) (xy 18.796 -45.085) (xy 18.796 -45.466) (xy 19.304 -45.466)
				)
			)
		)
	)
)
